(kicad_pcb
	(version 20260206)
	(generator "pcbnew")
	(generator_version "10.0")
	(general
		(thickness 1.6)
		(legacy_teardrops no)
	)
	(paper "A4")
	(title_block
		(title "01162023_DA0F0TEBIF0_F0T_Expander_BD_F_brd_V02_OCP.brd")
		(comment 1 "Grand Teton / footprints 931-937 of 9728")
	)
	(layers
		(0 "F.Cu" signal "TOP")
		(4 "In1.Cu" signal "GND")
		(6 "In2.Cu" signal "VCC")
		(8 "In3.Cu" signal "VCC1")
		(10 "In4.Cu" signal "GND1")
		(12 "In5.Cu" signal "IN1")
		(14 "In6.Cu" signal "GND2")
		(16 "In7.Cu" signal "IN2")
		(18 "In8.Cu" signal "GND3")
		(20 "In9.Cu" signal "IN3")
		(22 "In10.Cu" signal "GND4")
		(24 "In11.Cu" signal "IN4")
		(26 "In12.Cu" signal "GND5")
		(28 "In13.Cu" signal "IN5")
		(30 "In14.Cu" signal "GND6")
		(32 "In15.Cu" signal "IN6")
		(34 "In16.Cu" signal "GND7")
		(2 "B.Cu" signal "BOTTOM")
		(9 "F.Adhes" user "F.Adhesive")
		(11 "B.Adhes" user "B.Adhesive")
		(13 "F.Paste" user "Package Geometry/Pastemask Top")
		(15 "B.Paste" user "Package Geometry/Pastemask Bottom")
		(5 "F.SilkS" user "Ref Des/Silkscreen Top")
		(7 "B.SilkS" user "Ref Des/Silkscreen Bottom")
		(1 "F.Mask" user "Board Geometry/Soldermask Top")
		(3 "B.Mask" user "Board Geometry/Soldermask Bottom")
		(17 "Dwgs.User" user "User.Drawings")
		(19 "Cmts.User" user "User.Comments")
		(21 "Eco1.User" user "User.Eco1")
		(23 "Eco2.User" user "User.Eco2")
		(25 "Edge.Cuts" user "Board Geometry/Outline")
		(27 "Margin" user)
		(31 "F.CrtYd" user "Package Geometry/Place Bound Top")
		(29 "B.CrtYd" user "Package Geometry/Place Bound Bottom")
		(35 "F.Fab" user "Ref Des/Assembly Top")
		(33 "B.Fab" user "Ref Des/Assembly Bottom")
	)
	(footprint ""
		(layer "F.Cu")
		(at 268.402816 -91.478354 180)
		(property "Reference" "R1063"
			(at 0 0 180)
			(layer "F.SilkS")
			(hide yes)
			(effects
				(font
					(size 1.27 1.27)
				)
			)
		)
		(property "Value" ""
			(at 0 0 180)
			(layer "F.Fab")
			(effects
				(font
					(size 1.27 1.27)
				)
			)
		)
		(duplicate_pad_numbers_are_jumpers no)
		(fp_line
			(start 0.7874 0.4064)
			(end -0.7874 0.4064)
			(stroke
				(width 0.1524)
				(type default)
			)
			(layer "F.SilkS")
		)
		(fp_line
			(start 0.7874 -0.4064)
			(end 0.7874 0.4064)
			(stroke
				(width 0.1524)
				(type default)
			)
			(layer "F.SilkS")
		)
		(fp_line
			(start -0.7874 0.4064)
			(end -0.7874 -0.4064)
			(stroke
				(width 0.1524)
				(type default)
			)
			(layer "F.SilkS")
		)
		(fp_line
			(start -0.7874 -0.4064)
			(end 0.7874 -0.4064)
			(stroke
				(width 0.1524)
				(type default)
			)
			(layer "F.SilkS")
		)
		(fp_line
			(start 0.67945 0.3048)
			(end 0.120396 0.3048)
			(stroke
				(width 0.1)
				(type default)
			)
			(layer "F.Fab")
		)
		(fp_line
			(start 0.67945 -0.3048)
			(end 0.67945 0.3048)
			(stroke
				(width 0.1)
				(type default)
			)
			(layer "F.Fab")
		)
		(fp_line
			(start 0.12065 -0.2794)
			(end 0.12065 -0.3048)
			(stroke
				(width 0.1)
				(type default)
			)
			(layer "F.Fab")
		)
		(fp_line
			(start 0.12065 -0.3048)
			(end 0.67945 -0.3048)
			(stroke
				(width 0.1)
				(type default)
			)
			(layer "F.Fab")
		)
		(fp_line
			(start 0.120396 0.3048)
			(end 0.120396 0.2794)
			(stroke
				(width 0.1)
				(type default)
			)
			(layer "F.Fab")
		)
		(fp_line
			(start 0.120396 0.2794)
			(end -0.12065 0.2794)
			(stroke
				(width 0.1)
				(type default)
			)
			(layer "F.Fab")
		)
		(fp_line
			(start -0.12065 0.3048)
			(end -0.67945 0.3048)
			(stroke
				(width 0.1)
				(type default)
			)
			(layer "F.Fab")
		)
		(fp_line
			(start -0.12065 0.2794)
			(end -0.12065 0.3048)
			(stroke
				(width 0.1)
				(type default)
			)
			(layer "F.Fab")
		)
		(fp_line
			(start -0.12065 -0.2794)
			(end 0.12065 -0.2794)
			(stroke
				(width 0.1)
				(type default)
			)
			(layer "F.Fab")
		)
		(fp_line
			(start -0.12065 -0.305054)
			(end -0.12065 -0.2794)
			(stroke
				(width 0.1)
				(type default)
			)
			(layer "F.Fab")
		)
		(fp_line
			(start -0.67945 0.3048)
			(end -0.67945 -0.305054)
			(stroke
				(width 0.1)
				(type default)
			)
			(layer "F.Fab")
		)
		(fp_line
			(start -0.67945 -0.305054)
			(end -0.12065 -0.305054)
			(stroke
				(width 0.1)
				(type default)
			)
			(layer "F.Fab")
		)
		(pad "1" smd circle
			(at -0.40005 0 180)
			(size 0 0)
			(layers "F.Cu" "F.Mask" "F.Paste")
			(net "GND")
		)
		(pad "2" smd circle
			(at 0.40005 0 180)
			(size 0 0)
			(layers "F.Cu" "F.Mask" "F.Paste")
			(net "FM_CK440_MXCK_25M_100M")
		)
	)
	(footprint ""
		(layer "F.Cu")
		(at 57.650126 -50.96383 180)
		(property "Reference" "PC525"
			(at 0 0 180)
			(layer "F.SilkS")
			(hide yes)
			(effects
				(font
					(size 1.27 1.27)
				)
			)
		)
		(property "Value" ""
			(at 0 0 180)
			(layer "F.Fab")
			(effects
				(font
					(size 1.27 1.27)
				)
			)
		)
		(duplicate_pad_numbers_are_jumpers no)
		(fp_line
			(start 1.524 0.762)
			(end -1.524 0.762)
			(stroke
				(width 0.1524)
				(type default)
			)
			(layer "F.SilkS")
		)
		(fp_line
			(start 1.524 -0.762)
			(end 1.524 0.762)
			(stroke
				(width 0.1524)
				(type default)
			)
			(layer "F.SilkS")
		)
		(fp_line
			(start -1.524 0.762)
			(end -1.524 -0.762)
			(stroke
				(width 0.1524)
				(type default)
			)
			(layer "F.SilkS")
		)
		(fp_line
			(start -1.524 -0.762)
			(end 1.524 -0.762)
			(stroke
				(width 0.1524)
				(type default)
			)
			(layer "F.SilkS")
		)
		(fp_line
			(start 1.1049 0.724916)
			(end 1.1049 -0.724916)
			(stroke
				(width 0.1)
				(type default)
			)
			(layer "F.Fab")
		)
		(fp_line
			(start 1.1049 -0.724916)
			(end -1.1049 -0.724916)
			(stroke
				(width 0.1)
				(type default)
			)
			(layer "F.Fab")
		)
		(fp_line
			(start -1.1049 0.724916)
			(end 1.1049 0.724916)
			(stroke
				(width 0.1)
				(type default)
			)
			(layer "F.Fab")
		)
		(fp_line
			(start -1.1049 -0.724916)
			(end -1.1049 0.724916)
			(stroke
				(width 0.1)
				(type default)
			)
			(layer "F.Fab")
		)
		(pad "1" smd rect
			(at -0.889 0)
			(size 1.016 1.27)
			(layers "F.Cu" "F.Mask" "F.Paste")
			(net "P3V3_SSD2")
		)
		(pad "2" smd rect
			(at 0.889 0)
			(size 1.016 1.27)
			(layers "F.Cu" "F.Mask" "F.Paste")
			(net "GND")
		)
	)
	(footprint ""
		(layer "F.Cu")
		(at 230.682038 -37.025072)
		(property "Reference" "R5685"
			(at 0 0 0)
			(layer "F.SilkS")
			(hide yes)
			(effects
				(font
					(size 1.27 1.27)
				)
			)
		)
		(property "Value" ""
			(at 0 0 0)
			(layer "F.Fab")
			(effects
				(font
					(size 1.27 1.27)
				)
			)
		)
		(duplicate_pad_numbers_are_jumpers no)
		(fp_line
			(start -0.7874 -0.4064)
			(end 0.7874 -0.4064)
			(stroke
				(width 0.1524)
				(type default)
			)
			(layer "F.SilkS")
		)
		(fp_line
			(start -0.7874 0.4064)
			(end -0.7874 -0.4064)
			(stroke
				(width 0.1524)
				(type default)
			)
			(layer "F.SilkS")
		)
		(fp_line
			(start 0.7874 -0.4064)
			(end 0.7874 0.4064)
			(stroke
				(width 0.1524)
				(type default)
			)
			(layer "F.SilkS")
		)
		(fp_line
			(start 0.7874 0.4064)
			(end -0.7874 0.4064)
			(stroke
				(width 0.1524)
				(type default)
			)
			(layer "F.SilkS")
		)
		(fp_line
			(start -0.67945 -0.305054)
			(end -0.12065 -0.305054)
			(stroke
				(width 0.1)
				(type default)
			)
			(layer "F.Fab")
		)
		(fp_line
			(start -0.67945 0.3048)
			(end -0.67945 -0.305054)
			(stroke
				(width 0.1)
				(type default)
			)
			(layer "F.Fab")
		)
		(fp_line
			(start -0.12065 -0.305054)
			(end -0.12065 -0.2794)
			(stroke
				(width 0.1)
				(type default)
			)
			(layer "F.Fab")
		)
		(fp_line
			(start -0.12065 -0.2794)
			(end 0.12065 -0.2794)
			(stroke
				(width 0.1)
				(type default)
			)
			(layer "F.Fab")
		)
		(fp_line
			(start -0.12065 0.2794)
			(end -0.12065 0.3048)
			(stroke
				(width 0.1)
				(type default)
			)
			(layer "F.Fab")
		)
		(fp_line
			(start -0.12065 0.3048)
			(end -0.67945 0.3048)
			(stroke
				(width 0.1)
				(type default)
			)
			(layer "F.Fab")
		)
		(fp_line
			(start 0.120396 0.2794)
			(end -0.12065 0.2794)
			(stroke
				(width 0.1)
				(type default)
			)
			(layer "F.Fab")
		)
		(fp_line
			(start 0.120396 0.3048)
			(end 0.120396 0.2794)
			(stroke
				(width 0.1)
				(type default)
			)
			(layer "F.Fab")
		)
		(fp_line
			(start 0.12065 -0.3048)
			(end 0.67945 -0.3048)
			(stroke
				(width 0.1)
				(type default)
			)
			(layer "F.Fab")
		)
		(fp_line
			(start 0.12065 -0.2794)
			(end 0.12065 -0.3048)
			(stroke
				(width 0.1)
				(type default)
			)
			(layer "F.Fab")
		)
		(fp_line
			(start 0.67945 -0.3048)
			(end 0.67945 0.3048)
			(stroke
				(width 0.1)
				(type default)
			)
			(layer "F.Fab")
		)
		(fp_line
			(start 0.67945 0.3048)
			(end 0.120396 0.3048)
			(stroke
				(width 0.1)
				(type default)
			)
			(layer "F.Fab")
		)
		(pad "1" smd circle
			(at -0.40005 0)
			(size 0 0)
			(layers "F.Cu" "F.Mask" "F.Paste")
			(net "RST_SMB_SSD_R_N")
		)
		(pad "2" smd circle
			(at 0.40005 0)
			(size 0 0)
			(layers "F.Cu" "F.Mask" "F.Paste")
			(net "RST_SMB_SSD8_N")
		)
	)
	(footprint ""
		(layer "F.Cu")
		(at 384.938524 -111.895382)
		(property "Reference" "C682"
			(at 0 0 0)
			(layer "F.SilkS")
			(hide yes)
			(effects
				(font
					(size 1.27 1.27)
				)
			)
		)
		(property "Value" ""
			(at 0 0 0)
			(layer "F.Fab")
			(effects
				(font
					(size 1.27 1.27)
				)
			)
		)
		(duplicate_pad_numbers_are_jumpers no)
		(fp_line
			(start -0.299974 -0.150114)
			(end 0.299974 -0.150114)
			(stroke
				(width 0.1)
				(type default)
			)
			(layer "F.Fab")
		)
		(fp_line
			(start -0.299974 0.150114)
			(end -0.299974 -0.150114)
			(stroke
				(width 0.1)
				(type default)
			)
			(layer "F.Fab")
		)
		(fp_line
			(start 0.299974 -0.150114)
			(end 0.299974 0.150114)
			(stroke
				(width 0.1)
				(type default)
			)
			(layer "F.Fab")
		)
		(fp_line
			(start 0.299974 0.150114)
			(end -0.299974 0.150114)
			(stroke
				(width 0.1)
				(type default)
			)
			(layer "F.Fab")
		)
		(pad "1" smd rect
			(at -0.2667 0)
			(size 0.3048 0.381)
			(layers "F.Cu" "F.Mask" "F.Paste")
			(net "P5E_PEX3_STN1_TX_DN<23>")
		)
		(pad "2" smd rect
			(at 0.2667 0)
			(size 0.3048 0.381)
			(layers "F.Cu" "F.Mask" "F.Paste")
			(net "P5E_PEX3_STN1_TX_C_DN<23>")
		)
	)
	(footprint ""
		(layer "F.Cu")
		(at 140.074142 -180.977286 180)
		(property "Reference" "R1106"
			(at 0 0 180)
			(layer "F.SilkS")
			(hide yes)
			(effects
				(font
					(size 1.27 1.27)
				)
			)
		)
		(property "Value" ""
			(at 0 0 180)
			(layer "F.Fab")
			(effects
				(font
					(size 1.27 1.27)
				)
			)
		)
		(duplicate_pad_numbers_are_jumpers no)
		(fp_line
			(start 0.7874 0.4064)
			(end -0.7874 0.4064)
			(stroke
				(width 0.1524)
				(type default)
			)
			(layer "F.SilkS")
		)
		(fp_line
			(start 0.67945 0.3048)
			(end 0.120396 0.3048)
			(stroke
				(width 0.1)
				(type default)
			)
			(layer "F.Fab")
		)
		(fp_line
			(start 0.67945 -0.3048)
			(end 0.67945 0.3048)
			(stroke
				(width 0.1)
				(type default)
			)
			(layer "F.Fab")
		)
		(fp_line
			(start 0.12065 -0.2794)
			(end 0.12065 -0.3048)
			(stroke
				(width 0.1)
				(type default)
			)
			(layer "F.Fab")
		)
		(fp_line
			(start 0.12065 -0.3048)
			(end 0.67945 -0.3048)
			(stroke
				(width 0.1)
				(type default)
			)
			(layer "F.Fab")
		)
		(fp_line
			(start 0.120396 0.3048)
			(end 0.120396 0.2794)
			(stroke
				(width 0.1)
				(type default)
			)
			(layer "F.Fab")
		)
		(fp_line
			(start 0.120396 0.2794)
			(end -0.12065 0.2794)
			(stroke
				(width 0.1)
				(type default)
			)
			(layer "F.Fab")
		)
		(fp_line
			(start -0.12065 0.3048)
			(end -0.67945 0.3048)
			(stroke
				(width 0.1)
				(type default)
			)
			(layer "F.Fab")
		)
		(fp_line
			(start -0.12065 0.2794)
			(end -0.12065 0.3048)
			(stroke
				(width 0.1)
				(type default)
			)
			(layer "F.Fab")
		)
		(fp_line
			(start -0.12065 -0.2794)
			(end 0.12065 -0.2794)
			(stroke
				(width 0.1)
				(type default)
			)
			(layer "F.Fab")
		)
		(fp_line
			(start -0.12065 -0.305054)
			(end -0.12065 -0.2794)
			(stroke
				(width 0.1)
				(type default)
			)
			(layer "F.Fab")
		)
		(fp_line
			(start -0.67945 0.3048)
			(end -0.67945 -0.305054)
			(stroke
				(width 0.1)
				(type default)
			)
			(layer "F.Fab")
		)
		(fp_line
			(start -0.67945 -0.305054)
			(end -0.12065 -0.305054)
			(stroke
				(width 0.1)
				(type default)
			)
			(layer "F.Fab")
		)
		(pad "1" smd circle
			(at -0.40005 0 180)
			(size 0 0)
			(layers "F.Cu" "F.Mask" "F.Paste")
			(net "CLK_100M_DB2000QL_NIC5_R_DN")
		)
		(pad "2" smd circle
			(at 0.40005 0 180)
			(size 0 0)
			(layers "F.Cu" "F.Mask" "F.Paste")
			(net "CLK_100M_DB2000QL_NIC5_DN")
		)
	)
	(footprint ""
		(layer "F.Cu")
		(at 38.7604 -97.1804 180)
		(property "Reference" "R8"
			(at 0 0 180)
			(layer "F.SilkS")
			(hide yes)
			(effects
				(font
					(size 1.27 1.27)
				)
			)
		)
		(property "Value" ""
			(at 0 0 180)
			(layer "F.Fab")
			(effects
				(font
					(size 1.27 1.27)
				)
			)
		)
		(duplicate_pad_numbers_are_jumpers no)
		(fp_line
			(start 0.7874 0.4064)
			(end -0.7874 0.4064)
			(stroke
				(width 0.1524)
				(type default)
			)
			(layer "F.SilkS")
		)
		(fp_line
			(start 0.7874 -0.4064)
			(end 0.7874 0.4064)
			(stroke
				(width 0.1524)
				(type default)
			)
			(layer "F.SilkS")
		)
		(fp_line
			(start -0.7874 0.4064)
			(end -0.7874 -0.4064)
			(stroke
				(width 0.1524)
				(type default)
			)
			(layer "F.SilkS")
		)
		(fp_line
			(start -0.7874 -0.4064)
			(end 0.7874 -0.4064)
			(stroke
				(width 0.1524)
				(type default)
			)
			(layer "F.SilkS")
		)
		(fp_line
			(start 0.67945 0.3048)
			(end 0.120396 0.3048)
			(stroke
				(width 0.1)
				(type default)
			)
			(layer "F.Fab")
		)
		(fp_line
			(start 0.67945 -0.3048)
			(end 0.67945 0.3048)
			(stroke
				(width 0.1)
				(type default)
			)
			(layer "F.Fab")
		)
		(fp_line
			(start 0.12065 -0.2794)
			(end 0.12065 -0.3048)
			(stroke
				(width 0.1)
				(type default)
			)
			(layer "F.Fab")
		)
		(fp_line
			(start 0.12065 -0.3048)
			(end 0.67945 -0.3048)
			(stroke
				(width 0.1)
				(type default)
			)
			(layer "F.Fab")
		)
		(fp_line
			(start 0.120396 0.3048)
			(end 0.120396 0.2794)
			(stroke
				(width 0.1)
				(type default)
			)
			(layer "F.Fab")
		)
		(fp_line
			(start 0.120396 0.2794)
			(end -0.12065 0.2794)
			(stroke
				(width 0.1)
				(type default)
			)
			(layer "F.Fab")
		)
		(fp_line
			(start -0.12065 0.3048)
			(end -0.67945 0.3048)
			(stroke
				(width 0.1)
				(type default)
			)
			(layer "F.Fab")
		)
		(fp_line
			(start -0.12065 0.2794)
			(end -0.12065 0.3048)
			(stroke
				(width 0.1)
				(type default)
			)
			(layer "F.Fab")
		)
		(fp_line
			(start -0.12065 -0.2794)
			(end 0.12065 -0.2794)
			(stroke
				(width 0.1)
				(type default)
			)
			(layer "F.Fab")
		)
		(fp_line
			(start -0.12065 -0.305054)
			(end -0.12065 -0.2794)
			(stroke
				(width 0.1)
				(type default)
			)
			(layer "F.Fab")
		)
		(fp_line
			(start -0.67945 0.3048)
			(end -0.67945 -0.305054)
			(stroke
				(width 0.1)
				(type default)
			)
			(layer "F.Fab")
		)
		(fp_line
			(start -0.67945 -0.305054)
			(end -0.12065 -0.305054)
			(stroke
				(width 0.1)
				(type default)
			)
			(layer "F.Fab")
		)
		(pad "1" smd circle
			(at -0.40005 0 180)
			(size 0 0)
			(layers "F.Cu" "F.Mask" "F.Paste")
			(net "PRSNTB3_NIC0_N")
		)
		(pad "2" smd circle
			(at 0.40005 0 180)
			(size 0 0)
			(layers "F.Cu" "F.Mask" "F.Paste")
			(net "P3V3_AUX")
		)
	)
	(footprint ""
		(layer "F.Cu")
		(at 330.327 -245.237 -90)
		(property "Reference" "R1785"
			(at 0 0 270)
			(layer "F.SilkS")
			(hide yes)
			(effects
				(font
					(size 1.27 1.27)
				)
			)
		)
		(property "Value" ""
			(at 0 0 270)
			(layer "F.Fab")
			(effects
				(font
					(size 1.27 1.27)
				)
			)
		)
		(duplicate_pad_numbers_are_jumpers no)
		(fp_line
			(start -0.7874 0.4064)
			(end -0.7874 -0.4064)
			(stroke
				(width 0.1524)
				(type default)
			)
			(layer "F.SilkS")
		)
		(fp_line
			(start 0.7874 0.4064)
			(end -0.7874 0.4064)
			(stroke
				(width 0.1524)
				(type default)
			)
			(layer "F.SilkS")
		)
		(fp_line
			(start -0.7874 -0.4064)
			(end 0.7874 -0.4064)
			(stroke
				(width 0.1524)
				(type default)
			)
			(layer "F.SilkS")
		)
		(fp_line
			(start 0.7874 -0.4064)
			(end 0.7874 0.4064)
			(stroke
				(width 0.1524)
				(type default)
			)
			(layer "F.SilkS")
		)
		(fp_line
			(start -0.67945 0.3048)
			(end -0.67945 -0.305054)
			(stroke
				(width 0.1)
				(type default)
			)
			(layer "F.Fab")
		)
		(fp_line
			(start -0.12065 0.3048)
			(end -0.67945 0.3048)
			(stroke
				(width 0.1)
				(type default)
			)
			(layer "F.Fab")
		)
		(fp_line
			(start 0.120396 0.3048)
			(end 0.120396 0.2794)
			(stroke
				(width 0.1)
				(type default)
			)
			(layer "F.Fab")
		)
		(fp_line
			(start 0.67945 0.3048)
			(end 0.120396 0.3048)
			(stroke
				(width 0.1)
				(type default)
			)
			(layer "F.Fab")
		)
		(fp_line
			(start -0.12065 0.2794)
			(end -0.12065 0.3048)
			(stroke
				(width 0.1)
				(type default)
			)
			(layer "F.Fab")
		)
		(fp_line
			(start 0.120396 0.2794)
			(end -0.12065 0.2794)
			(stroke
				(width 0.1)
				(type default)
			)
			(layer "F.Fab")
		)
		(fp_line
			(start -0.12065 -0.2794)
			(end 0.12065 -0.2794)
			(stroke
				(width 0.1)
				(type default)
			)
			(layer "F.Fab")
		)
		(fp_line
			(start 0.12065 -0.2794)
			(end 0.12065 -0.3048)
			(stroke
				(width 0.1)
				(type default)
			)
			(layer "F.Fab")
		)
		(fp_line
			(start 0.12065 -0.3048)
			(end 0.67945 -0.3048)
			(stroke
				(width 0.1)
				(type default)
			)
			(layer "F.Fab")
		)
		(fp_line
			(start 0.67945 -0.3048)
			(end 0.67945 0.3048)
			(stroke
				(width 0.1)
				(type default)
			)
			(layer "F.Fab")
		)
		(fp_line
			(start -0.67945 -0.305054)
			(end -0.12065 -0.305054)
			(stroke
				(width 0.1)
				(type default)
			)
			(layer "F.Fab")
		)
		(fp_line
			(start -0.12065 -0.305054)
			(end -0.12065 -0.2794)
			(stroke
				(width 0.1)
				(type default)
			)
			(layer "F.Fab")
		)
		(pad "1" smd circle
			(at -0.40005 0 270)
			(size 0 0)
			(layers "F.Cu" "F.Mask" "F.Paste")
			(net "P3V3_AUX")
		)
		(pad "2" smd circle
			(at 0.40005 0 270)
			(size 0 0)
			(layers "F.Cu" "F.Mask" "F.Paste")
			(net "RST_MB_PERST_1_N")
		)
	)
)
